# T6G (Grand Teton) — schematic netlist excerpt (pin names and nets, part order shuffled) for the footprints in the layout excerpt that follows; sources: Cadence DE-HDL packaged netlist, KiCad conversion of 04192023_DAF0TMB3IC0_F0TG_MB_C_brd_V02_OCP.brd

PR6615  Q_RES  1K 1% CHIP  pkg 0402LF  page 362 : A = P3V3_AUX ; B = TP_P0V9_RETIMER_CPU0_VRHOT
R2800  Q_RES  0 5% EMPTY  pkg 0402LF  page 240 : A = SMB_FAN_3V3AUX_R_SCL ; B = SMB_FAN_3V3AUX_BUF_SCL
C334  Q_CAP  0.1UF 10V 10% X7S  pkg C0201  page 334 : A = P0V9_CPU1_RT1_2A ; B = GND

(kicad_pcb
	(version 20260206)
	(generator "pcbnew")
	(generator_version "10.0")
	(general
		(thickness 1.6)
		(legacy_teardrops no)
	)
	(paper "A4")
	(title_block
		(title "04192023_DAF0TMB3IC0_F0TG_MB_C_brd_V02_OCP.brd")
		(comment 1 "Grand Teton / footprints 6017-6019 of 8354")
	)
	(layers
		(0 "F.Cu" signal "TOP")
		(4 "In1.Cu" signal "GND")
		(6 "In2.Cu" signal "IN1")
		(8 "In3.Cu" signal "GND1")
		(10 "In4.Cu" signal "IN2")
		(12 "In5.Cu" signal "GND2")
		(14 "In6.Cu" signal "IN3")
		(16 "In7.Cu" signal "GND3")
		(18 "In8.Cu" signal "VCC")
		(20 "In9.Cu" signal "VCC1")
		(22 "In10.Cu" signal "GND4")
		(24 "In11.Cu" signal "IN4")
		(26 "In12.Cu" signal "GND5")
		(28 "In13.Cu" signal "IN5")
		(30 "In14.Cu" signal "GND6")
		(32 "In15.Cu" signal "IN6")
		(34 "In16.Cu" signal "GND7")
		(2 "B.Cu" signal "BOTTOM")
		(9 "F.Adhes" user "F.Adhesive")
		(11 "B.Adhes" user "B.Adhesive")
		(13 "F.Paste" user "Package Geometry/Pastemask Top")
		(15 "B.Paste" user "Package Geometry/Pastemask Bottom")
		(5 "F.SilkS" user "Ref Des/Silkscreen Top")
		(7 "B.SilkS" user "Ref Des/Silkscreen Bottom")
		(1 "F.Mask" user "Board Geometry/Soldermask Top")
		(3 "B.Mask" user "Board Geometry/Soldermask Bottom")
		(17 "Dwgs.User" user "User.Drawings")
		(19 "Cmts.User" user "User.Comments")
		(21 "Eco1.User" user "User.Eco1")
		(23 "Eco2.User" user "User.Eco2")
		(25 "Edge.Cuts" user "Board Geometry/Outline")
		(27 "Margin" user)
		(31 "F.CrtYd" user "Package Geometry/Place Bound Top")
		(29 "B.CrtYd" user "Package Geometry/Place Bound Bottom")
		(35 "F.Fab" user "Ref Des/Assembly Top")
		(33 "B.Fab" user "Ref Des/Assembly Bottom")
	)
	(footprint ""
		(layer "B.Cu")
		(at 182.225188 -418.423598 -90)
		(property "Reference" "R2800"
			(at 0 0 90)
			(layer "B.SilkS")
			(hide yes)
			(effects
				(font
					(size 1.27 1.27)
				)
				(justify mirror)
			)
		)
		(property "Value" ""
			(at 0 0 90)
			(layer "B.Fab")
			(effects
				(font
					(size 1.27 1.27)
				)
				(justify mirror)
			)
		)
		(duplicate_pad_numbers_are_jumpers no)
		(fp_line
			(start -0.7874 0.4064)
			(end 0.7874 0.4064)
			(stroke
				(width 0.1524)
				(type default)
			)
			(layer "B.SilkS")
		)
		(fp_line
			(start 0.7874 0.4064)
			(end 0.7874 -0.4064)
			(stroke
				(width 0.1524)
				(type default)
			)
			(layer "B.SilkS")
		)
		(fp_line
			(start -0.7874 -0.4064)
			(end -0.7874 0.4064)
			(stroke
				(width 0.1524)
				(type default)
			)
			(layer "B.SilkS")
		)
		(fp_line
			(start 0.7874 -0.4064)
			(end -0.7874 -0.4064)
			(stroke
				(width 0.1524)
				(type default)
			)
			(layer "B.SilkS")
		)
		(fp_line
			(start -0.67945 0.3048)
			(end -0.120396 0.3048)
			(stroke
				(width 0.1)
				(type default)
			)
			(layer "B.Fab")
		)
		(fp_line
			(start -0.120396 0.3048)
			(end -0.120396 0.2794)
			(stroke
				(width 0.1)
				(type default)
			)
			(layer "B.Fab")
		)
		(fp_line
			(start 0.12065 0.3048)
			(end 0.67945 0.3048)
			(stroke
				(width 0.1)
				(type default)
			)
			(layer "B.Fab")
		)
		(fp_line
			(start 0.67945 0.3048)
			(end 0.67945 -0.305054)
			(stroke
				(width 0.1)
				(type default)
			)
			(layer "B.Fab")
		)
		(fp_line
			(start -0.120396 0.2794)
			(end 0.12065 0.2794)
			(stroke
				(width 0.1)
				(type default)
			)
			(layer "B.Fab")
		)
		(fp_line
			(start 0.12065 0.2794)
			(end 0.12065 0.3048)
			(stroke
				(width 0.1)
				(type default)
			)
			(layer "B.Fab")
		)
		(fp_line
			(start -0.12065 -0.2794)
			(end -0.12065 -0.3048)
			(stroke
				(width 0.1)
				(type default)
			)
			(layer "B.Fab")
		)
		(fp_line
			(start 0.12065 -0.2794)
			(end -0.12065 -0.2794)
			(stroke
				(width 0.1)
				(type default)
			)
			(layer "B.Fab")
		)
		(fp_line
			(start -0.67945 -0.3048)
			(end -0.67945 0.3048)
			(stroke
				(width 0.1)
				(type default)
			)
			(layer "B.Fab")
		)
		(fp_line
			(start -0.12065 -0.3048)
			(end -0.67945 -0.3048)
			(stroke
				(width 0.1)
				(type default)
			)
			(layer "B.Fab")
		)
		(fp_line
			(start 0.12065 -0.305054)
			(end 0.12065 -0.2794)
			(stroke
				(width 0.1)
				(type default)
			)
			(layer "B.Fab")
		)
		(fp_line
			(start 0.67945 -0.305054)
			(end 0.12065 -0.305054)
			(stroke
				(width 0.1)
				(type default)
			)
			(layer "B.Fab")
		)
		(pad "1" smd circle
			(at 0.40005 0 90)
			(size 0 0)
			(layers "B.Cu" "B.Mask" "B.Paste")
			(net "SMB_FAN_3V3AUX_R_SCL")
		)
		(pad "2" smd circle
			(at -0.40005 0 90)
			(size 0 0)
			(layers "B.Cu" "B.Mask" "B.Paste")
			(net "SMB_FAN_3V3AUX_BUF_SCL")
		)
	)
	(footprint ""
		(layer "B.Cu")
		(at 83.646264 -388.011162 -90)
		(property "Reference" "C334"
			(at 0 0 90)
			(layer "B.SilkS")
			(hide yes)
			(effects
				(font
					(size 1.27 1.27)
				)
				(justify mirror)
			)
		)
		(property "Value" ""
			(at 0 0 90)
			(layer "B.Fab")
			(effects
				(font
					(size 1.27 1.27)
				)
				(justify mirror)
			)
		)
		(duplicate_pad_numbers_are_jumpers no)
		(fp_line
			(start -0.299974 0.150114)
			(end 0.299974 0.150114)
			(stroke
				(width 0.1)
				(type default)
			)
			(layer "B.Fab")
		)
		(fp_line
			(start 0.299974 0.150114)
			(end 0.299974 -0.150114)
			(stroke
				(width 0.1)
				(type default)
			)
			(layer "B.Fab")
		)
		(fp_line
			(start -0.299974 -0.150114)
			(end -0.299974 0.150114)
			(stroke
				(width 0.1)
				(type default)
			)
			(layer "B.Fab")
		)
		(fp_line
			(start 0.299974 -0.150114)
			(end -0.299974 -0.150114)
			(stroke
				(width 0.1)
				(type default)
			)
			(layer "B.Fab")
		)
		(pad "1" smd rect
			(at 0.2667 0 90)
			(size 0.3048 0.381)
			(layers "B.Cu" "B.Mask" "B.Paste")
			(net "P0V9_CPU1_RT1_2A")
		)
		(pad "2" smd rect
			(at -0.2667 0 90)
			(size 0.3048 0.381)
			(layers "B.Cu" "B.Mask" "B.Paste")
			(net "GND")
		)
	)
	(footprint ""
		(layer "B.Cu")
		(at 438.766966 -425.184824 -90)
		(property "Reference" "PR6615"
			(at 0 0 90)
			(layer "B.SilkS")
			(hide yes)
			(effects
				(font
					(size 1.27 1.27)
				)
				(justify mirror)
			)
		)
		(property "Value" ""
			(at 0 0 90)
			(layer "B.Fab")
			(effects
				(font
					(size 1.27 1.27)
				)
				(justify mirror)
			)
		)
		(duplicate_pad_numbers_are_jumpers no)
		(fp_line
			(start -0.7874 0.4064)
			(end 0.7874 0.4064)
			(stroke
				(width 0.1524)
				(type default)
			)
			(layer "B.SilkS")
		)
		(fp_line
			(start 0.7874 0.4064)
			(end 0.7874 -0.4064)
			(stroke
				(width 0.1524)
				(type default)
			)
			(layer "B.SilkS")
		)
		(fp_line
			(start -0.7874 -0.4064)
			(end -0.7874 0.4064)
			(stroke
				(width 0.1524)
				(type default)
			)
			(layer "B.SilkS")
		)
		(fp_line
			(start 0.7874 -0.4064)
			(end -0.7874 -0.4064)
			(stroke
				(width 0.1524)
				(type default)
			)
			(layer "B.SilkS")
		)
		(fp_line
			(start -0.67945 0.3048)
			(end -0.120396 0.3048)
			(stroke
				(width 0.1)
				(type default)
			)
			(layer "B.Fab")
		)
		(fp_line
			(start -0.120396 0.3048)
			(end -0.120396 0.2794)
			(stroke
				(width 0.1)
				(type default)
			)
			(layer "B.Fab")
		)
		(fp_line
			(start 0.12065 0.3048)
			(end 0.67945 0.3048)
			(stroke
				(width 0.1)
				(type default)
			)
			(layer "B.Fab")
		)
		(fp_line
			(start 0.67945 0.3048)
			(end 0.67945 -0.305054)
			(stroke
				(width 0.1)
				(type default)
			)
			(layer "B.Fab")
		)
		(fp_line
			(start -0.120396 0.2794)
			(end 0.12065 0.2794)
			(stroke
				(width 0.1)
				(type default)
			)
			(layer "B.Fab")
		)
		(fp_line
			(start 0.12065 0.2794)
			(end 0.12065 0.3048)
			(stroke
				(width 0.1)
				(type default)
			)
			(layer "B.Fab")
		)
		(fp_line
			(start -0.12065 -0.2794)
			(end -0.12065 -0.3048)
			(stroke
				(width 0.1)
				(type default)
			)
			(layer "B.Fab")
		)
		(fp_line
			(start 0.12065 -0.2794)
			(end -0.12065 -0.2794)
			(stroke
				(width 0.1)
				(type default)
			)
			(layer "B.Fab")
		)
		(fp_line
			(start -0.67945 -0.3048)
			(end -0.67945 0.3048)
			(stroke
				(width 0.1)
				(type default)
			)
			(layer "B.Fab")
		)
		(fp_line
			(start -0.12065 -0.3048)
			(end -0.67945 -0.3048)
			(stroke
				(width 0.1)
				(type default)
			)
			(layer "B.Fab")
		)
		(fp_line
			(start 0.12065 -0.305054)
			(end 0.12065 -0.2794)
			(stroke
				(width 0.1)
				(type default)
			)
			(layer "B.Fab")
		)
		(fp_line
			(start 0.67945 -0.305054)
			(end 0.12065 -0.305054)
			(stroke
				(width 0.1)
				(type default)
			)
			(layer "B.Fab")
		)
		(pad "1" smd circle
			(at 0.40005 0 90)
			(size 0 0)
			(layers "B.Cu" "B.Mask" "B.Paste")
			(net "P3V3_AUX")
		)
		(pad "2" smd circle
			(at -0.40005 0 90)
			(size 0 0)
			(layers "B.Cu" "B.Mask" "B.Paste")
			(net "TP_P0V9_RETIMER_CPU0_VRHOT")
		)
	)
)
